(kicad_pcb
	(version 20260206)
	(generator "pcbnew")
	(generator_version "10.0")
	(general
		(thickness 1.6)
		(legacy_teardrops no)
	)
	(paper "A4")
	(title_block
		(title "Wiwynn_Tioga_Pass_MB.brd")
		(comment 1 "Tioga Pass / footprints 1543-1548 of 4770")
	)
	(layers
		(0 "F.Cu" signal "TOP")
		(4 "In1.Cu" signal "L2GND")
		(6 "In2.Cu" signal "L3")
		(8 "In3.Cu" signal "L4GND")
		(10 "In4.Cu" signal "L5")
		(12 "In5.Cu" signal "L6GND")
		(14 "In6.Cu" signal "L7VCC")
		(16 "In7.Cu" signal "L8VCC")
		(18 "In8.Cu" signal "L9GND")
		(20 "In9.Cu" signal "L10")
		(22 "In10.Cu" signal "L11GND")
		(24 "In11.Cu" signal "L12")
		(26 "In12.Cu" signal "L13GND")
		(2 "B.Cu" signal "BOTTOM")
		(9 "F.Adhes" user "F.Adhesive")
		(11 "B.Adhes" user "B.Adhesive")
		(13 "F.Paste" user "Package Geometry/Pastemask Top")
		(15 "B.Paste" user "Package Geometry/Pastemask Bottom")
		(5 "F.SilkS" user "Ref Des/Silkscreen Top")
		(7 "B.SilkS" user "Ref Des/Silkscreen Bottom")
		(1 "F.Mask" user "Board Geometry/Soldermask Top")
		(3 "B.Mask" user "Board Geometry/Soldermask Bottom")
		(17 "Dwgs.User" user "User.Drawings")
		(19 "Cmts.User" user "User.Comments")
		(21 "Eco1.User" user "User.Eco1")
		(23 "Eco2.User" user "User.Eco2")
		(25 "Edge.Cuts" user "Board Geometry/Outline")
		(27 "Margin" user)
		(31 "F.CrtYd" user "Package Geometry/Place Bound Top")
		(29 "B.CrtYd" user "Package Geometry/Place Bound Bottom")
		(35 "F.Fab" user "Ref Des/Assembly Top")
		(33 "B.Fab" user "Ref Des/Assembly Bottom")
	)
	(footprint ""
		(layer "F.Cu")
		(at 352.7298 -100.29063 90)
		(property "Reference" "CT70"
			(at 0.86233 -0.5842 0)
			(unlocked yes)
			(layer "F.SilkS")
			(effects
				(font
					(size 0.7874 0.5842)
					(thickness 0.1524)
				)
				(justify left)
			)
		)
		(property "Value" ""
			(at 0 0 90)
			(layer "F.Fab")
			(effects
				(font
					(size 1.27 1.27)
				)
			)
		)
		(duplicate_pad_numbers_are_jumpers no)
		(fp_poly
			(pts
				(xy 0.3048 -0.1016) (xy 0.3048 0.9906) (xy -0.3048 0.9906) (xy -0.3048 -0.1016)
			)
			(stroke
				(width 0)
				(type default)
			)
			(fill no)
			(layer "F.CrtYd")
		)
		(fp_line
			(start 0.3048 -0.1016)
			(end -0.3048 -0.1016)
			(stroke
				(width 0.1)
				(type default)
			)
			(layer "F.Fab")
		)
		(fp_line
			(start -0.3048 -0.1016)
			(end -0.3048 0.9906)
			(stroke
				(width 0.1)
				(type default)
			)
			(layer "F.Fab")
		)
		(fp_line
			(start 0.3048 0.9906)
			(end 0.3048 -0.1016)
			(stroke
				(width 0.1)
				(type default)
			)
			(layer "F.Fab")
		)
		(fp_line
			(start -0.3048 0.9906)
			(end 0.3048 0.9906)
			(stroke
				(width 0.1)
				(type default)
			)
			(layer "F.Fab")
		)
		(pad "1" smd rect
			(at 0 0 90)
			(size 0.508 0.508)
			(layers "F.Cu" "F.Mask" "F.Paste")
			(net "VR_PVCCIO_CPU0_AIREF1")
		)
		(pad "2" smd rect
			(at 0 0.889 90)
			(size 0.508 0.508)
			(layers "F.Cu" "F.Mask" "F.Paste")
			(net "GND")
		)
		(zone
			(layer "F.Cu")
			(hatch none 0.5)
			(connect_pads
				(clearance 0)
			)
			(min_thickness 0.25)
			(keepout
				(tracks allowed)
				(vias not_allowed)
				(pads allowed)
				(copperpour not_allowed)
				(footprints allowed)
			)
			(placement
				(enabled no)
				(sheetname "")
			)
			(fill
				(thermal_gap 0.5)
				(thermal_bridge_width 0.5)
				(island_removal_mode 0)
			)
			(polygon
				(pts
					(xy 352.9838 -100.03663) (xy 352.9838 -100.54463) (xy 353.3648 -100.54463) (xy 353.3648 -100.03663)
				)
			)
		)
		(zone
			(layer "F.Cu")
			(hatch none 0.5)
			(connect_pads
				(clearance 0)
			)
			(min_thickness 0.25)
			(keepout
				(tracks not_allowed)
				(vias allowed)
				(pads allowed)
				(copperpour not_allowed)
				(footprints allowed)
			)
			(placement
				(enabled no)
				(sheetname "")
			)
			(fill
				(thermal_gap 0.5)
				(thermal_bridge_width 0.5)
				(island_removal_mode 0)
			)
			(polygon
				(pts
					(xy 353.3648 -100.03663) (xy 353.3648 -100.54463) (xy 352.9838 -100.54463) (xy 352.9838 -100.03663)
				)
			)
		)
	)
	(footprint ""
		(layer "F.Cu")
		(at 43.311064 -38.008306 180)
		(property "Reference" "C1F7"
			(at 6.17347 4.1656 270)
			(unlocked yes)
			(layer "F.SilkS")
			(effects
				(font
					(size 0.7874 0.5842)
					(thickness 0.1524)
				)
			)
		)
		(property "Value" ""
			(at 0 0 180)
			(layer "F.Fab")
			(effects
				(font
					(size 1.27 1.27)
				)
			)
		)
		(duplicate_pad_numbers_are_jumpers no)
		(fp_line
			(start 5.1435 9.271)
			(end 1.4097 9.271)
			(stroke
				(width 0.1524)
				(type default)
			)
			(layer "F.SilkS")
		)
		(fp_line
			(start 5.1435 -0.127)
			(end 5.1435 9.271)
			(stroke
				(width 0.1524)
				(type default)
			)
			(layer "F.SilkS")
		)
		(fp_line
			(start 4.3815 -1.016)
			(end 5.1435 -0.127)
			(stroke
				(width 0.1524)
				(type default)
			)
			(layer "F.SilkS")
		)
		(fp_line
			(start 1.8415 2.0955)
			(end 1.4097 2.0955)
			(stroke
				(width 0.1524)
				(type default)
			)
			(layer "F.SilkS")
		)
		(fp_line
			(start 1.8415 -1.016)
			(end 4.3815 -1.016)
			(stroke
				(width 0.1524)
				(type default)
			)
			(layer "F.SilkS")
		)
		(fp_line
			(start 1.8415 -2.0955)
			(end 1.8415 2.0955)
			(stroke
				(width 0.1524)
				(type default)
			)
			(layer "F.SilkS")
		)
		(fp_line
			(start 1.4097 -2.0955)
			(end 1.8415 -2.0955)
			(stroke
				(width 0.1524)
				(type default)
			)
			(layer "F.SilkS")
		)
		(fp_line
			(start -1.4097 9.271)
			(end -5.1435 9.271)
			(stroke
				(width 0.1524)
				(type default)
			)
			(layer "F.SilkS")
		)
		(fp_line
			(start -1.4097 -2.0955)
			(end -1.8415 -2.0955)
			(stroke
				(width 0.1524)
				(type default)
			)
			(layer "F.SilkS")
		)
		(fp_line
			(start -1.8415 2.0955)
			(end -1.4097 2.0955)
			(stroke
				(width 0.1524)
				(type default)
			)
			(layer "F.SilkS")
		)
		(fp_line
			(start -1.8415 -2.0955)
			(end -1.8415 2.0955)
			(stroke
				(width 0.1524)
				(type default)
			)
			(layer "F.SilkS")
		)
		(fp_line
			(start -4.3815 -1.016)
			(end -1.8415 -1.016)
			(stroke
				(width 0.1524)
				(type default)
			)
			(layer "F.SilkS")
		)
		(fp_line
			(start -5.1435 9.271)
			(end -5.1435 -0.127)
			(stroke
				(width 0.1524)
				(type default)
			)
			(layer "F.SilkS")
		)
		(fp_line
			(start -5.1435 -0.127)
			(end -4.3815 -1.016)
			(stroke
				(width 0.1524)
				(type default)
			)
			(layer "F.SilkS")
		)
		(fp_poly
			(pts
				(xy -5.14604 -0.12954) (xy -4.38404 -1.01346) (xy 4.37896 -1.016) (xy 5.1435 -0.12954) (xy 5.14096 9.271)
				(xy -5.14604 9.27354)
			)
			(stroke
				(width 0)
				(type default)
			)
			(fill no)
			(layer "F.CrtYd")
		)
		(fp_line
			(start 5.1435 9.271)
			(end -5.1435 9.271)
			(stroke
				(width 0.1)
				(type default)
			)
			(layer "F.Fab")
		)
		(fp_line
			(start 5.1435 -0.127)
			(end 5.1435 9.271)
			(stroke
				(width 0.1)
				(type default)
			)
			(layer "F.Fab")
		)
		(fp_line
			(start 4.3815 -1.016)
			(end 5.1435 -0.127)
			(stroke
				(width 0.1)
				(type default)
			)
			(layer "F.Fab")
		)
		(fp_line
			(start -4.3815 -1.016)
			(end 4.3815 -1.016)
			(stroke
				(width 0.1)
				(type default)
			)
			(layer "F.Fab")
		)
		(fp_line
			(start -5.1435 9.271)
			(end -5.1435 -0.127)
			(stroke
				(width 0.1)
				(type default)
			)
			(layer "F.Fab")
		)
		(fp_line
			(start -5.1435 -0.127)
			(end -4.3815 -1.016)
			(stroke
				(width 0.1)
				(type default)
			)
			(layer "F.Fab")
		)
		(fp_circle
			(center 0 4.1275)
			(end -4.9911 4.1275)
			(stroke
				(width 0.1)
				(type default)
			)
			(fill no)
			(layer "F.Fab")
		)
		(pad "1" smd rect
			(at 0 0 180)
			(size 1.905 4.191)
			(layers "F.Cu" "F.Mask" "F.Paste")
			(net "P12V_STBY")
		)
		(pad "2" smd rect
			(at 0 8.255 180)
			(size 1.905 4.191)
			(layers "F.Cu" "F.Mask" "F.Paste")
			(net "GND")
		)
		(zone
			(layer "F.Cu")
			(hatch none 0.5)
			(connect_pads
				(clearance 0)
			)
			(min_thickness 0.25)
			(keepout
				(tracks allowed)
				(vias not_allowed)
				(pads allowed)
				(copperpour not_allowed)
				(footprints allowed)
			)
			(placement
				(enabled no)
				(sheetname "")
			)
			(fill
				(thermal_gap 0.5)
				(thermal_bridge_width 0.5)
				(island_removal_mode 0)
			)
			(polygon
				(pts
					(xy 48.454564 -47.279306) (xy 38.167564 -47.279306) (xy 38.167564 -37.881306) (xy 38.929564 -36.992306)
					(xy 47.692564 -36.992306) (xy 48.454564 -37.881306)
				)
			)
		)
	)
	(footprint ""
		(layer "F.Cu")
		(at 489.0262 -34.8742 -90)
		(property "Reference" "R25W127"
			(at -0.8382 -0.67818 270)
			(unlocked yes)
			(layer "F.SilkS")
			(effects
				(font
					(size 0.4064 0.254)
					(thickness 0.1524)
				)
				(justify left)
			)
		)
		(property "Value" ""
			(at 0 0 270)
			(layer "F.Fab")
			(effects
				(font
					(size 1.27 1.27)
				)
			)
		)
		(duplicate_pad_numbers_are_jumpers no)
		(fp_poly
			(pts
				(xy -0.2794 -0.1016) (xy 0.2794 -0.1016) (xy 0.2794 0.9906) (xy -0.2794 0.9906)
			)
			(stroke
				(width 0)
				(type default)
			)
			(fill no)
			(layer "F.CrtYd")
		)
		(fp_line
			(start -0.2794 0.9906)
			(end 0.2794 0.9906)
			(stroke
				(width 0.1)
				(type default)
			)
			(layer "F.Fab")
		)
		(fp_line
			(start 0.2794 0.9906)
			(end 0.2794 -0.1016)
			(stroke
				(width 0.1)
				(type default)
			)
			(layer "F.Fab")
		)
		(fp_line
			(start -0.2794 -0.1016)
			(end -0.2794 0.9906)
			(stroke
				(width 0.1)
				(type default)
			)
			(layer "F.Fab")
		)
		(fp_line
			(start 0.2794 -0.1016)
			(end -0.2794 -0.1016)
			(stroke
				(width 0.1)
				(type default)
			)
			(layer "F.Fab")
		)
		(pad "1" smd rect
			(at 0 0 270)
			(size 0.508 0.508)
			(layers "F.Cu" "F.Mask" "F.Paste")
			(net "V_IO_G_J")
		)
		(pad "2" smd rect
			(at 0 0.889 270)
			(size 0.508 0.508)
			(layers "F.Cu" "F.Mask" "F.Paste")
			(net "GND")
		)
		(zone
			(layer "F.Cu")
			(hatch none 0.5)
			(connect_pads
				(clearance 0)
			)
			(min_thickness 0.25)
			(keepout
				(tracks not_allowed)
				(vias allowed)
				(pads allowed)
				(copperpour not_allowed)
				(footprints allowed)
			)
			(placement
				(enabled no)
				(sheetname "")
			)
			(fill
				(thermal_gap 0.5)
				(thermal_bridge_width 0.5)
				(island_removal_mode 0)
			)
			(polygon
				(pts
					(xy 488.3912 -35.1282) (xy 488.3912 -34.6202) (xy 488.7722 -34.6202) (xy 488.7722 -35.1282)
				)
			)
		)
		(zone
			(layer "F.Cu")
			(hatch none 0.5)
			(connect_pads
				(clearance 0)
			)
			(min_thickness 0.25)
			(keepout
				(tracks allowed)
				(vias not_allowed)
				(pads allowed)
				(copperpour not_allowed)
				(footprints allowed)
			)
			(placement
				(enabled no)
				(sheetname "")
			)
			(fill
				(thermal_gap 0.5)
				(thermal_bridge_width 0.5)
				(island_removal_mode 0)
			)
			(polygon
				(pts
					(xy 488.7722 -35.1282) (xy 488.7722 -34.6202) (xy 488.3912 -34.6202) (xy 488.3912 -35.1282)
				)
			)
		)
	)
	(footprint ""
		(layer "F.Cu")
		(at 318.543432 -3.302 -90)
		(property "Reference" "C6G4"
			(at 0 0 270)
			(layer "F.SilkS")
			(hide yes)
			(effects
				(font
					(size 1.27 1.27)
				)
			)
		)
		(property "Value" ""
			(at 0 0 270)
			(layer "F.Fab")
			(effects
				(font
					(size 1.27 1.27)
				)
			)
		)
		(duplicate_pad_numbers_are_jumpers no)
		(fp_poly
			(pts
				(xy -0.4953 -0.2032) (xy 0.4953 -0.2032) (xy 0.4953 1.6002) (xy -0.4953 1.6002)
			)
			(stroke
				(width 0)
				(type default)
			)
			(fill no)
			(layer "F.CrtYd")
		)
		(fp_line
			(start -0.4953 1.6002)
			(end -0.4953 -0.2032)
			(stroke
				(width 0.1)
				(type default)
			)
			(layer "F.Fab")
		)
		(fp_line
			(start 0.4953 1.6002)
			(end -0.4953 1.6002)
			(stroke
				(width 0.1)
				(type default)
			)
			(layer "F.Fab")
		)
		(fp_line
			(start -0.4953 -0.2032)
			(end 0.4953 -0.2032)
			(stroke
				(width 0.1)
				(type default)
			)
			(layer "F.Fab")
		)
		(fp_line
			(start 0.4953 -0.2032)
			(end 0.4953 1.6002)
			(stroke
				(width 0.1)
				(type default)
			)
			(layer "F.Fab")
		)
		(pad "1" smd rect
			(at 0 0 270)
			(size 0.762 0.889)
			(layers "F.Cu" "F.Mask" "F.Paste")
			(net "PVPP_ABC")
		)
		(pad "2" smd rect
			(at 0 1.397 270)
			(size 0.762 0.889)
			(layers "F.Cu" "F.Mask" "F.Paste")
			(net "GND")
		)
		(zone
			(layer "F.Cu")
			(hatch none 0.5)
			(connect_pads
				(clearance 0)
			)
			(min_thickness 0.25)
			(keepout
				(tracks not_allowed)
				(vias allowed)
				(pads allowed)
				(copperpour not_allowed)
				(footprints allowed)
			)
			(placement
				(enabled no)
				(sheetname "")
			)
			(fill
				(thermal_gap 0.5)
				(thermal_bridge_width 0.5)
				(island_removal_mode 0)
			)
			(polygon
				(pts
					(xy 318.098932 -3.683) (xy 318.098932 -2.921) (xy 317.590932 -2.921) (xy 317.590932 -3.683)
				)
			)
		)
	)
	(footprint ""
		(layer "F.Cu")
		(at 153.543 -3.302 -90)
		(property "Reference" "C3G7"
			(at 0 0 270)
			(layer "F.SilkS")
			(hide yes)
			(effects
				(font
					(size 1.27 1.27)
				)
			)
		)
		(property "Value" ""
			(at 0 0 270)
			(layer "F.Fab")
			(effects
				(font
					(size 1.27 1.27)
				)
			)
		)
		(duplicate_pad_numbers_are_jumpers no)
		(fp_poly
			(pts
				(xy -0.4953 -0.2032) (xy 0.4953 -0.2032) (xy 0.4953 1.6002) (xy -0.4953 1.6002)
			)
			(stroke
				(width 0)
				(type default)
			)
			(fill no)
			(layer "F.CrtYd")
		)
		(fp_line
			(start -0.4953 1.6002)
			(end -0.4953 -0.2032)
			(stroke
				(width 0.1)
				(type default)
			)
			(layer "F.Fab")
		)
		(fp_line
			(start 0.4953 1.6002)
			(end -0.4953 1.6002)
			(stroke
				(width 0.1)
				(type default)
			)
			(layer "F.Fab")
		)
		(fp_line
			(start -0.4953 -0.2032)
			(end 0.4953 -0.2032)
			(stroke
				(width 0.1)
				(type default)
			)
			(layer "F.Fab")
		)
		(fp_line
			(start 0.4953 -0.2032)
			(end 0.4953 1.6002)
			(stroke
				(width 0.1)
				(type default)
			)
			(layer "F.Fab")
		)
		(pad "1" smd rect
			(at 0 0 270)
			(size 0.762 0.889)
			(layers "F.Cu" "F.Mask" "F.Paste")
			(net "PVPP_GHJ")
		)
		(pad "2" smd rect
			(at 0 1.397 270)
			(size 0.762 0.889)
			(layers "F.Cu" "F.Mask" "F.Paste")
			(net "GND")
		)
		(zone
			(layer "F.Cu")
			(hatch none 0.5)
			(connect_pads
				(clearance 0)
			)
			(min_thickness 0.25)
			(keepout
				(tracks not_allowed)
				(vias allowed)
				(pads allowed)
				(copperpour not_allowed)
				(footprints allowed)
			)
			(placement
				(enabled no)
				(sheetname "")
			)
			(fill
				(thermal_gap 0.5)
				(thermal_bridge_width 0.5)
				(island_removal_mode 0)
			)
			(polygon
				(pts
					(xy 153.0985 -3.683) (xy 153.0985 -2.921) (xy 152.5905 -2.921) (xy 152.5905 -3.683)
				)
			)
		)
	)
	(footprint ""
		(layer "F.Cu")
		(at 171.069 -74.041 180)
		(property "Reference" "R4D35"
			(at 0 0 180)
			(layer "F.SilkS")
			(hide yes)
			(effects
				(font
					(size 1.27 1.27)
				)
			)
		)
		(property "Value" ""
			(at 0 0 180)
			(layer "F.Fab")
			(effects
				(font
					(size 1.27 1.27)
				)
			)
		)
		(duplicate_pad_numbers_are_jumpers no)
		(fp_poly
			(pts
				(xy -0.2794 -0.1016) (xy 0.2794 -0.1016) (xy 0.2794 0.9906) (xy -0.2794 0.9906)
			)
			(stroke
				(width 0)
				(type default)
			)
			(fill no)
			(layer "F.CrtYd")
		)
		(fp_line
			(start 0.2794 0.9906)
			(end 0.2794 -0.1016)
			(stroke
				(width 0.1)
				(type default)
			)
			(layer "F.Fab")
		)
		(fp_line
			(start 0.2794 -0.1016)
			(end -0.2794 -0.1016)
			(stroke
				(width 0.1)
				(type default)
			)
			(layer "F.Fab")
		)
		(fp_line
			(start -0.2794 0.9906)
			(end 0.2794 0.9906)
			(stroke
				(width 0.1)
				(type default)
			)
			(layer "F.Fab")
		)
		(fp_line
			(start -0.2794 -0.1016)
			(end -0.2794 0.9906)
			(stroke
				(width 0.1)
				(type default)
			)
			(layer "F.Fab")
		)
		(pad "1" smd rect
			(at 0 0 180)
			(size 0.508 0.508)
			(layers "F.Cu" "F.Mask" "F.Paste")
			(net "P3V3_DB1200")
		)
		(pad "2" smd rect
			(at 0 0.889 180)
			(size 0.508 0.508)
			(layers "F.Cu" "F.Mask" "F.Paste")
			(net "FM_DB1200_SMB_SA0")
		)
		(zone
			(layer "F.Cu")
			(hatch none 0.5)
			(connect_pads
				(clearance 0)
			)
			(min_thickness 0.25)
			(keepout
				(tracks not_allowed)
				(vias allowed)
				(pads allowed)
				(copperpour not_allowed)
				(footprints allowed)
			)
			(placement
				(enabled no)
				(sheetname "")
			)
			(fill
				(thermal_gap 0.5)
				(thermal_bridge_width 0.5)
				(island_removal_mode 0)
			)
			(polygon
				(pts
					(xy 171.323 -74.676) (xy 170.815 -74.676) (xy 170.815 -74.295) (xy 171.323 -74.295)
				)
			)
		)
		(zone
			(layer "F.Cu")
			(hatch none 0.5)
			(connect_pads
				(clearance 0)
			)
			(min_thickness 0.25)
			(keepout
				(tracks allowed)
				(vias not_allowed)
				(pads allowed)
				(copperpour not_allowed)
				(footprints allowed)
			)
			(placement
				(enabled no)
				(sheetname "")
			)
			(fill
				(thermal_gap 0.5)
				(thermal_bridge_width 0.5)
				(island_removal_mode 0)
			)
			(polygon
				(pts
					(xy 171.323 -74.295) (xy 170.815 -74.295) (xy 170.815 -74.676) (xy 171.323 -74.676)
				)
			)
		)
	)
)
